(kicad_pcb
	(version 20260206)
	(generator "pcbnew")
	(generator_version "10.0")
	(general
		(thickness 1.21888)
		(legacy_teardrops no)
	)
	(paper "A4")
	(title_block
		(title "timecard-v9 — TimeCard-DC-V9_EXP.PcbDoc")
		(comment 1 "Time Appliance Project (Time Card) / footprints 159-164 of 402")
	)
	(layers
		(0 "F.Cu" signal "TOP")
		(4 "In1.Cu" signal "SGND")
		(6 "In2.Cu" signal "IN1")
		(8 "In3.Cu" signal "IN2")
		(10 "In4.Cu" signal "SGND1")
		(2 "B.Cu" signal "BOTTOM")
		(9 "F.Adhes" user "F.Adhesive")
		(11 "B.Adhes" user "B.Adhesive")
		(13 "F.Paste" user "Top Paste")
		(15 "B.Paste" user "Bottom Paste")
		(5 "F.SilkS" user "Top Overlay")
		(7 "B.SilkS" user "Bottom Overlay")
		(1 "F.Mask" user "Top Solder")
		(3 "B.Mask" user "Bottom Solder")
		(17 "Dwgs.User" user "User.Drawings")
		(19 "Cmts.User" user "User.Comments")
		(21 "Eco1.User" user "User.Eco1")
		(23 "Eco2.User" user "User.Eco2")
		(25 "Edge.Cuts" user)
		(27 "Margin" user)
		(31 "F.CrtYd" user "Top Courtyard")
		(29 "B.CrtYd" user "Bottom Courtyard")
		(35 "F.Fab" user "Top Component Center")
		(33 "B.Fab" user "Bottom Component Center")
	)
	(footprint "MUN12AD06-SM:MUN12AD06-SM_CYN"
		(layer "F.Cu")
		(at 179.3216 84.59122 180)
		(property "Reference" "U24"
			(at -1.26218 4.335689 0)
			(unlocked yes)
			(layer "F.SilkS")
			(effects
				(font
					(size 0.762 0.762)
					(thickness 0.2032)
				)
			)
		)
		(property "Value" "MUN12AD06-SM"
			(at 5.027645 -0.734819 180)
			(unlocked yes)
			(layer "F.SilkS")
			(hide yes)
			(effects
				(font
					(size 0.762 0.762)
					(thickness 0.2032)
				)
			)
		)
		(sheetname "03-POWER")
		(sheetfile "03-POWER.kicad_sch")
		(duplicate_pad_numbers_are_jumpers no)
		(fp_line
			(start 3.1242 3.1242)
			(end 2.00688 3.1242)
			(stroke
				(width 0.1524)
				(type solid)
			)
			(layer "F.SilkS")
		)
		(fp_line
			(start 3.1242 2.00688)
			(end 3.1242 3.1242)
			(stroke
				(width 0.1524)
				(type solid)
			)
			(layer "F.SilkS")
		)
		(fp_line
			(start 3.1242 -3.1242)
			(end 3.1242 -2.00687)
			(stroke
				(width 0.1524)
				(type solid)
			)
			(layer "F.SilkS")
		)
		(fp_line
			(start 3.1242 -3.1242)
			(end 2.00688 -3.1242)
			(stroke
				(width 0.1524)
				(type solid)
			)
			(layer "F.SilkS")
		)
		(fp_line
			(start -2.00688 3.1242)
			(end -3.1242 3.1242)
			(stroke
				(width 0.1524)
				(type solid)
			)
			(layer "F.SilkS")
		)
		(fp_line
			(start -2.00688 -3.1242)
			(end -3.1242 -3.1242)
			(stroke
				(width 0.1524)
				(type solid)
			)
			(layer "F.SilkS")
		)
		(fp_line
			(start -3.1242 2.00688)
			(end -3.1242 3.1242)
			(stroke
				(width 0.1524)
				(type solid)
			)
			(layer "F.SilkS")
		)
		(fp_line
			(start -3.1242 -3.1242)
			(end -3.1242 -2.00687)
			(stroke
				(width 0.1524)
				(type solid)
			)
			(layer "F.SilkS")
		)
		(fp_poly
			(pts
				(xy 1.7905 3.1496) (xy 1.4095 3.1496) (xy 1.4095 3.4036) (xy 1.7905 3.4036)
			)
			(stroke
				(width 0)
				(type default)
			)
			(fill yes)
			(layer "F.SilkS")
		)
		(fp_poly
			(pts
				(xy -1.4095 -3.1496) (xy -1.7905 -3.1496) (xy -1.7905 -3.4036) (xy -1.4095 -3.4036)
			)
			(stroke
				(width 0)
				(type default)
			)
			(fill yes)
			(layer "F.SilkS")
		)
		(fp_text user "*"
			(at -3.8481 -0.809415 180)
			(unlocked yes)
			(layer "F.SilkS")
			(effects
				(font
					(size 1.27 1.27)
					(thickness 0.0762)
				)
				(justify left bottom)
			)
		)
		(pad "1" smd rect
			(at -2.6416 -1.59999 90)
			(size 0.3302 0.508)
			(layers "F.Cu" "F.Mask" "F.Paste")
			(net "+12V")
			(solder_mask_margin 0)
			(solder_paste_margin 0)
		)
		(pad "2" smd rect
			(at -2.6416 -0.8 90)
			(size 0.3302 0.508)
			(layers "F.Cu" "F.Mask" "F.Paste")
			(net "P3V3_MUN_PHASE")
			(solder_mask_margin 0)
			(solder_paste_margin 0)
		)
		(pad "3" smd rect
			(at -2.6416 0 90)
			(size 0.3302 0.508)
			(layers "F.Cu" "F.Mask" "F.Paste")
			(net "P3V3_MUN_PHASE")
			(solder_mask_margin 0)
			(solder_paste_margin 0)
		)
		(pad "4" smd rect
			(at -2.6416 0.80001 90)
			(size 0.3302 0.508)
			(layers "F.Cu" "F.Mask" "F.Paste")
			(net "P3V3_MUN_PHASE")
			(solder_mask_margin 0)
			(solder_paste_margin 0)
		)
		(pad "5" smd rect
			(at -2.6416 1.6 90)
			(size 0.3302 0.508)
			(layers "F.Cu" "F.Mask" "F.Paste")
			(net "GND")
			(solder_mask_margin 0)
			(solder_paste_margin 0)
		)
		(pad "6" smd rect
			(at -1.6 2.6416)
			(size 0.3302 0.508)
			(layers "F.Cu" "F.Mask" "F.Paste")
			(net "GND")
			(solder_mask_margin 0)
			(solder_paste_margin 0)
		)
		(pad "7" smd rect
			(at -0.8 2.6416)
			(size 0.3302 0.508)
			(layers "F.Cu" "F.Mask" "F.Paste")
			(net "GND")
			(solder_mask_margin 0)
			(solder_paste_margin 0)
		)
		(pad "8" smd rect
			(at 0 2.6416)
			(size 0.3302 0.508)
			(layers "F.Cu" "F.Mask" "F.Paste")
			(net "NetR69_2")
			(solder_mask_margin 0)
			(solder_paste_margin 0)
		)
		(pad "9" smd rect
			(at 0.8 2.6416)
			(size 0.3302 0.508)
			(layers "F.Cu" "F.Mask" "F.Paste")
			(net "NetR70_1")
			(solder_mask_margin 0)
			(solder_paste_margin 0)
		)
		(pad "10" smd rect
			(at 1.6 2.6416)
			(size 0.3302 0.508)
			(layers "F.Cu" "F.Mask" "F.Paste")
			(net "P3V3_SENSE")
			(solder_mask_margin 0)
			(solder_paste_margin 0)
		)
		(pad "11" smd rect
			(at 2.6416 1.6 90)
			(size 0.3302 0.508)
			(layers "F.Cu" "F.Mask" "F.Paste")
			(net "P3V3_SENSE")
			(solder_mask_margin 0)
			(solder_paste_margin 0)
		)
		(pad "12" smd rect
			(at 2.6416 0.80001 90)
			(size 0.3302 0.508)
			(layers "F.Cu" "F.Mask" "F.Paste")
			(net "P3V3_SENSE")
			(solder_mask_margin 0)
			(solder_paste_margin 0)
		)
		(pad "13" smd rect
			(at 2.6416 0 90)
			(size 0.3302 0.508)
			(layers "F.Cu" "F.Mask" "F.Paste")
			(net "P3V3_SENSE")
			(solder_mask_margin 0)
			(solder_paste_margin 0)
		)
		(pad "14" smd rect
			(at 2.6416 -0.8 90)
			(size 0.3302 0.508)
			(layers "F.Cu" "F.Mask" "F.Paste")
			(net "P3V3_SENSE")
			(solder_mask_margin 0)
			(solder_paste_margin 0)
		)
		(pad "15" smd rect
			(at 2.6416 -1.59999 90)
			(size 0.3302 0.508)
			(layers "F.Cu" "F.Mask" "F.Paste")
			(net "GND")
			(solder_mask_margin 0)
			(solder_paste_margin 0)
		)
		(pad "16" smd rect
			(at 1.6 -2.6416)
			(size 0.3302 0.508)
			(layers "F.Cu" "F.Mask" "F.Paste")
			(net "P3V3_MUN_FB")
			(solder_mask_margin 0)
			(solder_paste_margin 0)
		)
		(pad "17" smd rect
			(at 0.8 -2.6416)
			(size 0.3302 0.508)
			(layers "F.Cu" "F.Mask" "F.Paste")
			(net "P3V3_MUN_VCC")
			(solder_mask_margin 0)
			(solder_paste_margin 0)
		)
		(pad "18" smd rect
			(at 0 -2.6416)
			(size 0.3302 0.508)
			(layers "F.Cu" "F.Mask" "F.Paste")
			(solder_mask_margin 0)
			(solder_paste_margin 0)
		)
		(pad "19" smd rect
			(at -0.8 -2.6416)
			(size 0.3302 0.508)
			(layers "F.Cu" "F.Mask" "F.Paste")
			(net "+12V")
			(solder_mask_margin 0)
			(solder_paste_margin 0)
		)
		(pad "20" smd rect
			(at -1.6 -2.6416)
			(size 0.3302 0.508)
			(layers "F.Cu" "F.Mask" "F.Paste")
			(net "+12V")
			(solder_mask_margin 0)
			(solder_paste_margin 0)
		)
		(pad "21" smd rect
			(at -0.91 -1.66999 180)
			(size 1.8796 0.3556)
			(layers "F.Cu" "F.Mask" "F.Paste")
			(net "+12V")
			(solder_mask_margin 0)
			(solder_paste_margin 0)
		)
		(pad "22" smd rect
			(at -0.91 -0.86 180)
			(size 1.8796 0.6604)
			(layers "F.Cu" "F.Mask" "F.Paste")
			(net "P3V3_MUN_PHASE")
			(solder_mask_margin 0)
			(solder_paste_margin 0)
		)
		(pad "23" smd rect
			(at -0.91 0.80001 180)
			(size 1.8796 2.1082)
			(layers "F.Cu" "F.Mask" "F.Paste")
			(net "GND")
			(solder_mask_margin 0)
			(solder_paste_margin 0)
		)
		(pad "24" smd rect
			(at 1.4 0.80001 180)
			(size 0.889 2.1082)
			(layers "F.Cu" "F.Mask" "F.Paste")
			(net "P3V3_SENSE")
			(solder_mask_margin 0)
			(solder_paste_margin 0)
		)
		(pad "25" smd rect
			(at 1.4 -1.2 180)
			(size 0.889 1.2954)
			(layers "F.Cu" "F.Mask" "F.Paste")
			(net "GND")
			(solder_mask_margin 0)
			(solder_paste_margin 0)
		)
	)
	(footprint "SamacSys:155124M173200"
		(layer "F.Cu")
		(at 67.4466 141.8162 90)
		(property "Reference" "D18"
			(at -0.3286 1.448069 270)
			(unlocked yes)
			(layer "F.SilkS")
			(effects
				(font
					(size 0.762 0.762)
					(thickness 0.2286)
				)
			)
		)
		(property "Value" "155124M173200"
			(at 7.1471 2.605271 90)
			(unlocked yes)
			(layer "F.SilkS")
			(hide yes)
			(effects
				(font
					(size 0.762 0.762)
					(thickness 0.2286)
				)
			)
		)
		(sheetname "02-USER_IO_STATUS")
		(sheetfile "02-USER_IO_STATUS.kicad_sch")
		(duplicate_pad_numbers_are_jumpers no)
		(fp_line
			(start -0.8 0.5)
			(end 0.8 0.5)
			(stroke
				(width 0.1)
				(type solid)
			)
			(layer "F.SilkS")
		)
		(fp_arc
			(start -2 -0.1)
			(mid -1.95 -0.05)
			(end -2 0)
			(stroke
				(width 0.381)
				(type solid)
			)
			(layer "F.SilkS")
		)
		(fp_arc
			(start -2 0)
			(mid -2.05 -0.05)
			(end -2 -0.1)
			(stroke
				(width 0.381)
				(type solid)
			)
			(layer "F.SilkS")
		)
		(pad "1" smd rect
			(at -1.4 0 180)
			(size 0.9 0.6)
			(layers "F.Cu" "F.Mask" "F.Paste")
			(net "+3.3V")
		)
		(pad "2" smd rect
			(at -0.45 -0.325 90)
			(size 0.6 0.55)
			(layers "F.Cu" "F.Mask" "F.Paste")
			(net "NetD18_2")
		)
		(pad "3" smd rect
			(at 0.45 -0.325 90)
			(size 0.6 0.55)
			(layers "F.Cu" "F.Mask" "F.Paste")
			(net "NetD18_3")
		)
		(pad "4" smd rect
			(at 1.4 0 180)
			(size 0.9 0.6)
			(layers "F.Cu" "F.Mask" "F.Paste")
			(net "NetD18_4")
		)
	)
	(footprint "Vault:RESC3216X89X64NL25T25"
		(layer "F.Cu")
		(at 93.0216 65.3162)
		(property "Reference" "R8"
			(at -0.4 -1.206655 0)
			(unlocked yes)
			(layer "F.SilkS")
			(effects
				(font
					(size 0.762 0.762)
					(thickness 0.2286)
				)
				(justify left bottom)
			)
		)
		(property "Value" "2mOhm_1%_1206"
			(at 16.2553 6.763245 0)
			(unlocked yes)
			(layer "F.SilkS")
			(hide yes)
			(effects
				(font
					(size 0.762 0.762)
					(thickness 0.2286)
				)
				(justify left bottom)
			)
		)
		(sheetname "03-POWER")
		(sheetfile "03-POWER.kicad_sch")
		(duplicate_pad_numbers_are_jumpers no)
		(fp_line
			(start -0.2 -0.825)
			(end 0.2 -0.825)
			(stroke
				(width 0.2)
				(type solid)
			)
			(layer "F.SilkS")
		)
		(fp_line
			(start -0.2 0.825)
			(end 0.2 0.825)
			(stroke
				(width 0.2)
				(type solid)
			)
			(layer "F.SilkS")
		)
		(pad "1" smd rect
			(at -1.325 0 90)
			(size 1.85 1.5)
			(layers "F.Cu" "F.Mask" "F.Paste")
			(net "P5V_SENSE")
		)
		(pad "2" smd rect
			(at 1.325 0 90)
			(size 1.85 1.5)
			(layers "F.Cu" "F.Mask" "F.Paste")
			(net "+5.0V")
		)
	)
	(footprint "Vault:RESC1005X40X25LL05T10"
		(layer "F.Cu")
		(at 227.3216 119.3162 180)
		(property "Reference" "R82"
			(at 2.2714 -0.126931 0)
			(unlocked yes)
			(layer "F.SilkS")
			(effects
				(font
					(size 0.762 0.762)
					(thickness 0.2286)
				)
			)
		)
		(property "Value" "10K_1%_0402"
			(at -2.579871 8.061915 90)
			(unlocked yes)
			(layer "F.SilkS")
			(hide yes)
			(effects
				(font
					(size 0.762 0.762)
					(thickness 0.2286)
				)
			)
		)
		(sheetname "09-USBUart_PPSMUX_UARTMUX")
		(sheetfile "09-USBUart_PPSMUX_UARTMUX.kicad_sch")
		(duplicate_pad_numbers_are_jumpers no)
		(pad "1" smd rect
			(at -0.375 0 270)
			(size 0.45 0.5)
			(layers "F.Cu" "F.Mask" "F.Paste")
			(net "NetC91_1")
		)
		(pad "2" smd rect
			(at 0.375 0 270)
			(size 0.45 0.5)
			(layers "F.Cu" "F.Mask" "F.Paste")
			(net "FTDI_VBUS")
		)
	)
	(footprint "SamacSys:SOP50P310X90-8N"
		(layer "F.Cu")
		(at 77.4216 101.9162 180)
		(property "Reference" "U8"
			(at -0.228595 1.773079 0)
			(unlocked yes)
			(layer "F.SilkS")
			(effects
				(font
					(size 0.762 0.762)
					(thickness 0.2286)
				)
			)
		)
		(property "Value" "NC7WV125K8X"
			(at 6.207715 2.884671 180)
			(unlocked yes)
			(layer "F.SilkS")
			(hide yes)
			(effects
				(font
					(size 0.762 0.762)
					(thickness 0.2286)
				)
			)
		)
		(sheetname "01-USER_IO")
		(sheetfile "01-USER_IO.kicad_sch")
		(duplicate_pad_numbers_are_jumpers no)
		(fp_line
			(start 0.8 1)
			(end -0.8 1)
			(stroke
				(width 0.2)
				(type solid)
			)
			(layer "F.SilkS")
		)
		(fp_line
			(start 0.8 -1)
			(end 0.8 1)
			(stroke
				(width 0.2)
				(type solid)
			)
			(layer "F.SilkS")
		)
		(fp_line
			(start 0.8 -1)
			(end -0.8 -1)
			(stroke
				(width 0.2)
				(type solid)
			)
			(layer "F.SilkS")
		)
		(fp_line
			(start -0.8 -1)
			(end -0.8 1)
			(stroke
				(width 0.2)
				(type solid)
			)
			(layer "F.SilkS")
		)
		(fp_line
			(start -1.15 -1.25)
			(end -2 -1.25)
			(stroke
				(width 0.2)
				(type solid)
			)
			(layer "F.SilkS")
		)
		(pad "1" smd rect
			(at -1.575 -0.75 180)
			(size 0.85 0.3)
			(layers "F.Cu" "F.Mask" "F.Paste")
			(net "ANT1_IO_OUT")
		)
		(pad "2" smd rect
			(at -1.575 -0.25 180)
			(size 0.85 0.3)
			(layers "F.Cu" "F.Mask" "F.Paste")
			(net "ANT1_OUT")
		)
		(pad "3" smd rect
			(at -1.575 0.25 180)
			(size 0.85 0.3)
			(layers "F.Cu" "F.Mask" "F.Paste")
			(net "ANT1_IN")
		)
		(pad "4" smd rect
			(at -1.575 0.75 180)
			(size 0.85 0.3)
			(layers "F.Cu" "F.Mask" "F.Paste")
			(net "GND")
		)
		(pad "5" smd rect
			(at 1.575 0.75 180)
			(size 0.85 0.3)
			(layers "F.Cu" "F.Mask" "F.Paste")
			(net "NetR25_1")
		)
		(pad "6" smd rect
			(at 1.575 0.25 180)
			(size 0.85 0.3)
			(layers "F.Cu" "F.Mask" "F.Paste")
			(net "NetR25_1")
		)
		(pad "7" smd rect
			(at 1.575 -0.25 180)
			(size 0.85 0.3)
			(layers "F.Cu" "F.Mask" "F.Paste")
			(net "ANT1_IO_IN")
		)
		(pad "8" smd rect
			(at 1.575 -0.75 180)
			(size 0.85 0.3)
			(layers "F.Cu" "F.Mask" "F.Paste")
			(net "+3.3V")
		)
	)
	(footprint "PI3A412ZHE:ZH16_PER"
		(layer "F.Cu")
		(at 193.6216 132.3162)
		(property "Reference" "U28"
			(at -0.39436 -3.693929 0)
			(unlocked yes)
			(layer "F.SilkS")
			(effects
				(font
					(size 0.762 0.762)
					(thickness 0.2032)
				)
			)
		)
		(property "Value" "PI3A412ZHE"
			(at 4.684 3.722871 0)
			(unlocked yes)
			(layer "F.SilkS")
			(hide yes)
			(effects
				(font
					(size 0.762 0.762)
					(thickness 0.2032)
				)
			)
		)
		(sheetname "11-M2_RCB_MUX")
		(sheetfile "11-M2_RCB_MUX.kicad_sch")
		(duplicate_pad_numbers_are_jumpers no)
		(fp_line
			(start -1.6764 -1.6764)
			(end -1.20974 -1.6764)
			(stroke
				(width 0.1524)
				(type solid)
			)
			(layer "F.SilkS")
		)
		(fp_line
			(start -1.6764 -1.20974)
			(end -1.6764 -1.6764)
			(stroke
				(width 0.1524)
				(type solid)
			)
			(layer "F.SilkS")
		)
		(fp_line
			(start -1.6764 1.6764)
			(end -1.6764 1.20974)
			(stroke
				(width 0.1524)
				(type solid)
			)
			(layer "F.SilkS")
		)
		(fp_line
			(start -1.6764 1.6764)
			(end -1.20974 1.6764)
			(stroke
				(width 0.1524)
				(type solid)
			)
			(layer "F.SilkS")
		)
		(fp_line
			(start 1.20974 -1.6764)
			(end 1.6764 -1.6764)
			(stroke
				(width 0.1524)
				(type solid)
			)
			(layer "F.SilkS")
		)
		(fp_line
			(start 1.20974 1.6764)
			(end 1.6764 1.6764)
			(stroke
				(width 0.1524)
				(type solid)
			)
			(layer "F.SilkS")
		)
		(fp_line
			(start 1.6764 -1.20974)
			(end 1.6764 -1.6764)
			(stroke
				(width 0.1524)
				(type solid)
			)
			(layer "F.SilkS")
		)
		(fp_line
			(start 1.6764 1.6764)
			(end 1.6764 1.20974)
			(stroke
				(width 0.1524)
				(type solid)
			)
			(layer "F.SilkS")
		)
		(fp_poly
			(pts
				(xy 2.1082 0.0595) (xy 2.3622 0.0595) (xy 2.3622 0.4405) (xy 2.1082 0.4405)
			)
			(stroke
				(width 0)
				(type default)
			)
			(fill yes)
			(layer "F.SilkS")
		)
		(fp_text user "*"
			(at -2.8067 -0.209425 0)
			(unlocked yes)
			(layer "F.SilkS")
			(effects
				(font
					(size 1.27 1.27)
					(thickness 0.0762)
				)
				(justify left bottom)
			)
		)
		(pad "1" smd rect
			(at -1.4478 -0.75 270)
			(size 0.254 0.8128)
			(layers "F.Cu" "F.Mask" "F.Paste")
			(net "RCB_GPS2_TX")
			(solder_mask_margin 0)
			(solder_paste_margin 0)
		)
		(pad "2" smd rect
			(at -1.4478 -0.25 270)
			(size 0.254 0.8128)
			(layers "F.Cu" "F.Mask" "F.Paste")
			(net "DIP_SW_GPS2_SEL")
			(solder_mask_margin 0)
			(solder_paste_margin 0)
		)
		(pad "3" smd rect
			(at -1.4478 0.25 270)
			(size 0.254 0.8128)
			(layers "F.Cu" "F.Mask" "F.Paste")
			(net "M2_GPS2_RX")
			(solder_mask_margin 0)
			(solder_paste_margin 0)
		)
		(pad "4" smd rect
			(at -1.4478 0.75 270)
			(size 0.254 0.8128)
			(layers "F.Cu" "F.Mask" "F.Paste")
			(net "NetR146_1")
			(solder_mask_margin 0)
			(solder_paste_margin 0)
		)
		(pad "5" smd rect
			(at -0.75 1.4478 180)
			(size 0.254 0.8128)
			(layers "F.Cu" "F.Mask" "F.Paste")
			(net "RCB_GPS2_RX")
			(solder_mask_margin 0)
			(solder_paste_margin 0)
		)
		(pad "6" smd rect
			(at -0.25 1.4478 180)
			(size 0.254 0.8128)
			(layers "F.Cu" "F.Mask" "F.Paste")
			(net "GND")
			(solder_mask_margin 0)
			(solder_paste_margin 0)
		)
		(pad "7" smd rect
			(at 0.25 1.4478 180)
			(size 0.254 0.8128)
			(layers "F.Cu" "F.Mask" "F.Paste")
			(net "M2_GPS2_TP1")
			(solder_mask_margin 0)
			(solder_paste_margin 0)
		)
		(pad "8" smd rect
			(at 0.75 1.4478 180)
			(size 0.254 0.8128)
			(layers "F.Cu" "F.Mask" "F.Paste")
			(net "NetR145_1")
			(solder_mask_margin 0)
			(solder_paste_margin 0)
		)
		(pad "9" smd rect
			(at 1.4478 0.75 270)
			(size 0.254 0.8128)
			(layers "F.Cu" "F.Mask" "F.Paste")
			(net "RCB_GPS2_TP1")
			(solder_mask_margin 0)
			(solder_paste_margin 0)
		)
		(pad "10" smd rect
			(at 1.4478 0.25 270)
			(size 0.254 0.8128)
			(layers "F.Cu" "F.Mask" "F.Paste")
			(net "DIP_SW_GPS2_SEL")
			(solder_mask_margin 0)
			(solder_paste_margin 0)
		)
		(pad "11" smd rect
			(at 1.4478 -0.25 270)
			(size 0.254 0.8128)
			(layers "F.Cu" "F.Mask" "F.Paste")
			(net "M2_GPS2_TP2")
			(solder_mask_margin 0)
			(solder_paste_margin 0)
		)
		(pad "12" smd rect
			(at 1.4478 -0.75 270)
			(size 0.254 0.8128)
			(layers "F.Cu" "F.Mask" "F.Paste")
			(net "NetR143_1")
			(solder_mask_margin 0)
			(solder_paste_margin 0)
		)
		(pad "13" smd rect
			(at 0.75 -1.4478 180)
			(size 0.254 0.8128)
			(layers "F.Cu" "F.Mask" "F.Paste")
			(net "RCB_GPS2_TP2")
			(solder_mask_margin 0)
			(solder_paste_margin 0)
		)
		(pad "14" smd rect
			(at 0.25 -1.4478 180)
			(size 0.254 0.8128)
			(layers "F.Cu" "F.Mask" "F.Paste")
			(net "+3.3V")
			(solder_mask_margin 0)
			(solder_paste_margin 0)
		)
		(pad "15" smd rect
			(at -0.25 -1.4478 180)
			(size 0.254 0.8128)
			(layers "F.Cu" "F.Mask" "F.Paste")
			(net "M2_GPS2_TX")
			(solder_mask_margin 0)
			(solder_paste_margin 0)
		)
		(pad "16" smd rect
			(at -0.75 -1.4478 180)
			(size 0.254 0.8128)
			(layers "F.Cu" "F.Mask" "F.Paste")
			(net "NetR142_1")
			(solder_mask_margin 0)
			(solder_paste_margin 0)
		)
		(pad "17" smd rect
			(at 0 0)
			(size 1.8034 1.8034)
			(layers "F.Cu" "F.Mask" "F.Paste")
			(net "GND")
			(solder_mask_margin 0)
			(solder_paste_margin 0)
		)
	)
)
